(kicad_pcb
	(version 20260206)
	(generator "pcbnew")
	(generator_version "10.0")
	(general
		(thickness 1.6)
		(legacy_teardrops no)
	)
	(paper "A4")
	(title_block
		(title "04192023_DAF0TMB3IC0_F0TG_MB_C_brd_V02_OCP.brd")
		(comment 1 "Grand Teton / footprints 1590-1595 of 8354")
	)
	(layers
		(0 "F.Cu" signal "TOP")
		(4 "In1.Cu" signal "GND")
		(6 "In2.Cu" signal "IN1")
		(8 "In3.Cu" signal "GND1")
		(10 "In4.Cu" signal "IN2")
		(12 "In5.Cu" signal "GND2")
		(14 "In6.Cu" signal "IN3")
		(16 "In7.Cu" signal "GND3")
		(18 "In8.Cu" signal "VCC")
		(20 "In9.Cu" signal "VCC1")
		(22 "In10.Cu" signal "GND4")
		(24 "In11.Cu" signal "IN4")
		(26 "In12.Cu" signal "GND5")
		(28 "In13.Cu" signal "IN5")
		(30 "In14.Cu" signal "GND6")
		(32 "In15.Cu" signal "IN6")
		(34 "In16.Cu" signal "GND7")
		(2 "B.Cu" signal "BOTTOM")
		(9 "F.Adhes" user "F.Adhesive")
		(11 "B.Adhes" user "B.Adhesive")
		(13 "F.Paste" user "Package Geometry/Pastemask Top")
		(15 "B.Paste" user "Package Geometry/Pastemask Bottom")
		(5 "F.SilkS" user "Ref Des/Silkscreen Top")
		(7 "B.SilkS" user "Ref Des/Silkscreen Bottom")
		(1 "F.Mask" user "Board Geometry/Soldermask Top")
		(3 "B.Mask" user "Board Geometry/Soldermask Bottom")
		(17 "Dwgs.User" user "User.Drawings")
		(19 "Cmts.User" user "User.Comments")
		(21 "Eco1.User" user "User.Eco1")
		(23 "Eco2.User" user "User.Eco2")
		(25 "Edge.Cuts" user "Board Geometry/Outline")
		(27 "Margin" user)
		(31 "F.CrtYd" user "Package Geometry/Place Bound Top")
		(29 "B.CrtYd" user "Package Geometry/Place Bound Bottom")
		(35 "F.Fab" user "Ref Des/Assembly Top")
		(33 "B.Fab" user "Ref Des/Assembly Bottom")
	)
	(footprint ""
		(layer "F.Cu")
		(at 213.835488 -136.31799 90)
		(property "Reference" "R1649"
			(at 0 0 90)
			(layer "F.SilkS")
			(hide yes)
			(effects
				(font
					(size 1.27 1.27)
				)
			)
		)
		(property "Value" ""
			(at 0 0 90)
			(layer "F.Fab")
			(effects
				(font
					(size 1.27 1.27)
				)
			)
		)
		(duplicate_pad_numbers_are_jumpers no)
		(fp_line
			(start 0.7874 -0.4064)
			(end 0.7874 0.4064)
			(stroke
				(width 0.1524)
				(type default)
			)
			(layer "F.SilkS")
		)
		(fp_line
			(start -0.7874 -0.4064)
			(end 0.7874 -0.4064)
			(stroke
				(width 0.1524)
				(type default)
			)
			(layer "F.SilkS")
		)
		(fp_line
			(start 0.7874 0.4064)
			(end -0.7874 0.4064)
			(stroke
				(width 0.1524)
				(type default)
			)
			(layer "F.SilkS")
		)
		(fp_line
			(start -0.7874 0.4064)
			(end -0.7874 -0.4064)
			(stroke
				(width 0.1524)
				(type default)
			)
			(layer "F.SilkS")
		)
		(fp_line
			(start -0.12065 -0.305054)
			(end -0.12065 -0.2794)
			(stroke
				(width 0.1)
				(type default)
			)
			(layer "F.Fab")
		)
		(fp_line
			(start -0.67945 -0.305054)
			(end -0.12065 -0.305054)
			(stroke
				(width 0.1)
				(type default)
			)
			(layer "F.Fab")
		)
		(fp_line
			(start 0.67945 -0.3048)
			(end 0.67945 0.3048)
			(stroke
				(width 0.1)
				(type default)
			)
			(layer "F.Fab")
		)
		(fp_line
			(start 0.12065 -0.3048)
			(end 0.67945 -0.3048)
			(stroke
				(width 0.1)
				(type default)
			)
			(layer "F.Fab")
		)
		(fp_line
			(start 0.12065 -0.2794)
			(end 0.12065 -0.3048)
			(stroke
				(width 0.1)
				(type default)
			)
			(layer "F.Fab")
		)
		(fp_line
			(start -0.12065 -0.2794)
			(end 0.12065 -0.2794)
			(stroke
				(width 0.1)
				(type default)
			)
			(layer "F.Fab")
		)
		(fp_line
			(start 0.120396 0.2794)
			(end -0.12065 0.2794)
			(stroke
				(width 0.1)
				(type default)
			)
			(layer "F.Fab")
		)
		(fp_line
			(start -0.12065 0.2794)
			(end -0.12065 0.3048)
			(stroke
				(width 0.1)
				(type default)
			)
			(layer "F.Fab")
		)
		(fp_line
			(start 0.67945 0.3048)
			(end 0.120396 0.3048)
			(stroke
				(width 0.1)
				(type default)
			)
			(layer "F.Fab")
		)
		(fp_line
			(start 0.120396 0.3048)
			(end 0.120396 0.2794)
			(stroke
				(width 0.1)
				(type default)
			)
			(layer "F.Fab")
		)
		(fp_line
			(start -0.12065 0.3048)
			(end -0.67945 0.3048)
			(stroke
				(width 0.1)
				(type default)
			)
			(layer "F.Fab")
		)
		(fp_line
			(start -0.67945 0.3048)
			(end -0.67945 -0.305054)
			(stroke
				(width 0.1)
				(type default)
			)
			(layer "F.Fab")
		)
		(pad "1" smd circle
			(at -0.40005 0 90)
			(size 0 0)
			(layers "F.Cu" "F.Mask" "F.Paste")
			(net "PVDD18_S5_P0")
		)
		(pad "2" smd circle
			(at 0.40005 0 90)
			(size 0 0)
			(layers "F.Cu" "F.Mask" "F.Paste")
			(net "CPU1_HDT_BYPASS_SEL")
		)
	)
	(footprint ""
		(layer "F.Cu")
		(at 163.703 -114.264948 180)
		(property "Reference" "R6039"
			(at 0 0 180)
			(layer "F.SilkS")
			(hide yes)
			(effects
				(font
					(size 1.27 1.27)
				)
			)
		)
		(property "Value" ""
			(at 0 0 180)
			(layer "F.Fab")
			(effects
				(font
					(size 1.27 1.27)
				)
			)
		)
		(duplicate_pad_numbers_are_jumpers no)
		(fp_line
			(start 0.7874 0.4064)
			(end -0.7874 0.4064)
			(stroke
				(width 0.1524)
				(type default)
			)
			(layer "F.SilkS")
		)
		(fp_line
			(start 0.7874 -0.4064)
			(end 0.7874 0.4064)
			(stroke
				(width 0.1524)
				(type default)
			)
			(layer "F.SilkS")
		)
		(fp_line
			(start -0.7874 0.4064)
			(end -0.7874 -0.4064)
			(stroke
				(width 0.1524)
				(type default)
			)
			(layer "F.SilkS")
		)
		(fp_line
			(start -0.7874 -0.4064)
			(end 0.7874 -0.4064)
			(stroke
				(width 0.1524)
				(type default)
			)
			(layer "F.SilkS")
		)
		(fp_line
			(start 0.67945 0.3048)
			(end 0.120396 0.3048)
			(stroke
				(width 0.1)
				(type default)
			)
			(layer "F.Fab")
		)
		(fp_line
			(start 0.67945 -0.3048)
			(end 0.67945 0.3048)
			(stroke
				(width 0.1)
				(type default)
			)
			(layer "F.Fab")
		)
		(fp_line
			(start 0.12065 -0.2794)
			(end 0.12065 -0.3048)
			(stroke
				(width 0.1)
				(type default)
			)
			(layer "F.Fab")
		)
		(fp_line
			(start 0.12065 -0.3048)
			(end 0.67945 -0.3048)
			(stroke
				(width 0.1)
				(type default)
			)
			(layer "F.Fab")
		)
		(fp_line
			(start 0.120396 0.3048)
			(end 0.120396 0.2794)
			(stroke
				(width 0.1)
				(type default)
			)
			(layer "F.Fab")
		)
		(fp_line
			(start 0.120396 0.2794)
			(end -0.12065 0.2794)
			(stroke
				(width 0.1)
				(type default)
			)
			(layer "F.Fab")
		)
		(fp_line
			(start -0.12065 0.3048)
			(end -0.67945 0.3048)
			(stroke
				(width 0.1)
				(type default)
			)
			(layer "F.Fab")
		)
		(fp_line
			(start -0.12065 0.2794)
			(end -0.12065 0.3048)
			(stroke
				(width 0.1)
				(type default)
			)
			(layer "F.Fab")
		)
		(fp_line
			(start -0.12065 -0.2794)
			(end 0.12065 -0.2794)
			(stroke
				(width 0.1)
				(type default)
			)
			(layer "F.Fab")
		)
		(fp_line
			(start -0.12065 -0.305054)
			(end -0.12065 -0.2794)
			(stroke
				(width 0.1)
				(type default)
			)
			(layer "F.Fab")
		)
		(fp_line
			(start -0.67945 0.3048)
			(end -0.67945 -0.305054)
			(stroke
				(width 0.1)
				(type default)
			)
			(layer "F.Fab")
		)
		(fp_line
			(start -0.67945 -0.305054)
			(end -0.12065 -0.305054)
			(stroke
				(width 0.1)
				(type default)
			)
			(layer "F.Fab")
		)
		(pad "1" smd circle
			(at -0.40005 0 180)
			(size 0 0)
			(layers "F.Cu" "F.Mask" "F.Paste")
			(net "OC_ALERT_N")
		)
		(pad "2" smd circle
			(at 0.40005 0 180)
			(size 0 0)
			(layers "F.Cu" "F.Mask" "F.Paste")
			(net "HSC_D_OC")
		)
	)
	(footprint ""
		(layer "F.Cu")
		(at 313.104022 -36.890706 180)
		(property "Reference" "C1347"
			(at 0 0 180)
			(layer "F.SilkS")
			(hide yes)
			(effects
				(font
					(size 1.27 1.27)
				)
			)
		)
		(property "Value" ""
			(at 0 0 180)
			(layer "F.Fab")
			(effects
				(font
					(size 1.27 1.27)
				)
			)
		)
		(duplicate_pad_numbers_are_jumpers no)
		(fp_line
			(start 0.7874 0.4064)
			(end -0.7874 0.4064)
			(stroke
				(width 0.1524)
				(type default)
			)
			(layer "F.SilkS")
		)
		(fp_line
			(start 0.7874 -0.4064)
			(end 0.7874 0.4064)
			(stroke
				(width 0.1524)
				(type default)
			)
			(layer "F.SilkS")
		)
		(fp_line
			(start -0.7874 0.4064)
			(end -0.7874 -0.4064)
			(stroke
				(width 0.1524)
				(type default)
			)
			(layer "F.SilkS")
		)
		(fp_line
			(start -0.7874 -0.4064)
			(end 0.7874 -0.4064)
			(stroke
				(width 0.1524)
				(type default)
			)
			(layer "F.SilkS")
		)
		(fp_line
			(start 0.67945 0.3048)
			(end 0.120396 0.3048)
			(stroke
				(width 0.1)
				(type default)
			)
			(layer "F.Fab")
		)
		(fp_line
			(start 0.67945 -0.3048)
			(end 0.67945 0.3048)
			(stroke
				(width 0.1)
				(type default)
			)
			(layer "F.Fab")
		)
		(fp_line
			(start 0.12065 -0.2794)
			(end 0.12065 -0.3048)
			(stroke
				(width 0.1)
				(type default)
			)
			(layer "F.Fab")
		)
		(fp_line
			(start 0.12065 -0.3048)
			(end 0.67945 -0.3048)
			(stroke
				(width 0.1)
				(type default)
			)
			(layer "F.Fab")
		)
		(fp_line
			(start 0.120396 0.3048)
			(end 0.120396 0.2794)
			(stroke
				(width 0.1)
				(type default)
			)
			(layer "F.Fab")
		)
		(fp_line
			(start 0.120396 0.2794)
			(end -0.12065 0.2794)
			(stroke
				(width 0.1)
				(type default)
			)
			(layer "F.Fab")
		)
		(fp_line
			(start -0.12065 0.3048)
			(end -0.67945 0.3048)
			(stroke
				(width 0.1)
				(type default)
			)
			(layer "F.Fab")
		)
		(fp_line
			(start -0.12065 0.2794)
			(end -0.12065 0.3048)
			(stroke
				(width 0.1)
				(type default)
			)
			(layer "F.Fab")
		)
		(fp_line
			(start -0.12065 -0.2794)
			(end 0.12065 -0.2794)
			(stroke
				(width 0.1)
				(type default)
			)
			(layer "F.Fab")
		)
		(fp_line
			(start -0.12065 -0.305054)
			(end -0.12065 -0.2794)
			(stroke
				(width 0.1)
				(type default)
			)
			(layer "F.Fab")
		)
		(fp_line
			(start -0.67945 0.3048)
			(end -0.67945 -0.305054)
			(stroke
				(width 0.1)
				(type default)
			)
			(layer "F.Fab")
		)
		(fp_line
			(start -0.67945 -0.305054)
			(end -0.12065 -0.305054)
			(stroke
				(width 0.1)
				(type default)
			)
			(layer "F.Fab")
		)
		(pad "1" smd circle
			(at -0.40005 0 180)
			(size 0 0)
			(layers "F.Cu" "F.Mask" "F.Paste")
			(net "MAX11617_VREF")
		)
		(pad "2" smd circle
			(at 0.40005 0 180)
			(size 0 0)
			(layers "F.Cu" "F.Mask" "F.Paste")
			(net "GND")
		)
	)
	(footprint ""
		(layer "F.Cu")
		(at 2.992628 -44.062904 90)
		(property "Reference" "R931"
			(at 0 0 90)
			(layer "F.SilkS")
			(hide yes)
			(effects
				(font
					(size 1.27 1.27)
				)
			)
		)
		(property "Value" ""
			(at 0 0 90)
			(layer "F.Fab")
			(effects
				(font
					(size 1.27 1.27)
				)
			)
		)
		(duplicate_pad_numbers_are_jumpers no)
		(fp_line
			(start 0.7874 -0.4064)
			(end 0.7874 0.4064)
			(stroke
				(width 0.1524)
				(type default)
			)
			(layer "F.SilkS")
		)
		(fp_line
			(start -0.7874 -0.4064)
			(end 0.7874 -0.4064)
			(stroke
				(width 0.1524)
				(type default)
			)
			(layer "F.SilkS")
		)
		(fp_line
			(start 0.7874 0.4064)
			(end -0.7874 0.4064)
			(stroke
				(width 0.1524)
				(type default)
			)
			(layer "F.SilkS")
		)
		(fp_line
			(start -0.7874 0.4064)
			(end -0.7874 -0.4064)
			(stroke
				(width 0.1524)
				(type default)
			)
			(layer "F.SilkS")
		)
		(fp_line
			(start -0.12065 -0.305054)
			(end -0.12065 -0.2794)
			(stroke
				(width 0.1)
				(type default)
			)
			(layer "F.Fab")
		)
		(fp_line
			(start -0.67945 -0.305054)
			(end -0.12065 -0.305054)
			(stroke
				(width 0.1)
				(type default)
			)
			(layer "F.Fab")
		)
		(fp_line
			(start 0.67945 -0.3048)
			(end 0.67945 0.3048)
			(stroke
				(width 0.1)
				(type default)
			)
			(layer "F.Fab")
		)
		(fp_line
			(start 0.12065 -0.3048)
			(end 0.67945 -0.3048)
			(stroke
				(width 0.1)
				(type default)
			)
			(layer "F.Fab")
		)
		(fp_line
			(start 0.12065 -0.2794)
			(end 0.12065 -0.3048)
			(stroke
				(width 0.1)
				(type default)
			)
			(layer "F.Fab")
		)
		(fp_line
			(start -0.12065 -0.2794)
			(end 0.12065 -0.2794)
			(stroke
				(width 0.1)
				(type default)
			)
			(layer "F.Fab")
		)
		(fp_line
			(start 0.120396 0.2794)
			(end -0.12065 0.2794)
			(stroke
				(width 0.1)
				(type default)
			)
			(layer "F.Fab")
		)
		(fp_line
			(start -0.12065 0.2794)
			(end -0.12065 0.3048)
			(stroke
				(width 0.1)
				(type default)
			)
			(layer "F.Fab")
		)
		(fp_line
			(start 0.67945 0.3048)
			(end 0.120396 0.3048)
			(stroke
				(width 0.1)
				(type default)
			)
			(layer "F.Fab")
		)
		(fp_line
			(start 0.120396 0.3048)
			(end 0.120396 0.2794)
			(stroke
				(width 0.1)
				(type default)
			)
			(layer "F.Fab")
		)
		(fp_line
			(start -0.12065 0.3048)
			(end -0.67945 0.3048)
			(stroke
				(width 0.1)
				(type default)
			)
			(layer "F.Fab")
		)
		(fp_line
			(start -0.67945 0.3048)
			(end -0.67945 -0.305054)
			(stroke
				(width 0.1)
				(type default)
			)
			(layer "F.Fab")
		)
		(pad "1" smd circle
			(at -0.40005 0 90)
			(size 0 0)
			(layers "F.Cu" "F.Mask" "F.Paste")
			(net "CPU1_XTRIG_L6")
		)
		(pad "2" smd circle
			(at 0.40005 0 90)
			(size 0 0)
			(layers "F.Cu" "F.Mask" "F.Paste")
			(net "CPU1_XTRIG_R1_L6")
		)
	)
	(footprint ""
		(layer "F.Cu")
		(at 343.994486 -20.08505 -90)
		(property "Reference" "Q11"
			(at -1.866138 -2.810002 90)
			(unlocked yes)
			(layer "F.SilkS")
			(effects
				(font
					(size 0.7874 0.5842)
					(thickness 0.1524)
				)
				(justify left)
			)
		)
		(property "Value" ""
			(at 0 0 270)
			(layer "F.Fab")
			(effects
				(font
					(size 1.27 1.27)
				)
			)
		)
		(duplicate_pad_numbers_are_jumpers no)
		(fp_line
			(start -1.332738 1.100074)
			(end -1.332738 -1.100074)
			(stroke
				(width 0.1524)
				(type default)
			)
			(layer "F.SilkS")
		)
		(fp_line
			(start 1.332738 1.100074)
			(end -1.332738 1.100074)
			(stroke
				(width 0.1524)
				(type default)
			)
			(layer "F.SilkS")
		)
		(fp_line
			(start 0 -0.541274)
			(end 0.4826 -1.100074)
			(stroke
				(width 0.1524)
				(type default)
			)
			(layer "F.SilkS")
		)
		(fp_line
			(start -1.332738 -1.100074)
			(end -0.4826 -1.100074)
			(stroke
				(width 0.1524)
				(type default)
			)
			(layer "F.SilkS")
		)
		(fp_line
			(start -0.4826 -1.100074)
			(end 0 -0.541274)
			(stroke
				(width 0.1524)
				(type default)
			)
			(layer "F.SilkS")
		)
		(fp_line
			(start 0.4826 -1.100074)
			(end 1.332738 -1.100074)
			(stroke
				(width 0.1524)
				(type default)
			)
			(layer "F.SilkS")
		)
		(fp_line
			(start 1.332738 -1.100074)
			(end 1.332738 1.100074)
			(stroke
				(width 0.1524)
				(type default)
			)
			(layer "F.SilkS")
		)
		(fp_poly
			(pts
				(xy -2.009902 -0.663702) (xy -2.711958 -0.312674) (xy -2.711958 -1.01473)
			)
			(stroke
				(width 0)
				(type default)
			)
			(fill yes)
			(layer "F.SilkS")
		)
		(fp_line
			(start -0.674878 1.100074)
			(end -0.674878 -1.100074)
			(stroke
				(width 0.1)
				(type default)
			)
			(layer "F.Fab")
		)
		(fp_line
			(start 0.674878 1.100074)
			(end -0.674878 1.100074)
			(stroke
				(width 0.1)
				(type default)
			)
			(layer "F.Fab")
		)
		(fp_line
			(start -0.674878 -1.100074)
			(end 0.674878 -1.100074)
			(stroke
				(width 0.1)
				(type default)
			)
			(layer "F.Fab")
		)
		(fp_line
			(start 0.674878 -1.100074)
			(end 0.674878 1.100074)
			(stroke
				(width 0.1)
				(type default)
			)
			(layer "F.Fab")
		)
		(fp_poly
			(pts
				(xy -2.2352 -0.298958) (xy -2.2352 -1.001014) (xy -1.533144 -0.649986)
			)
			(stroke
				(width 0)
				(type default)
			)
			(fill yes)
			(layer "F.Fab")
		)
		(pad "1" smd rect
			(at -0.94996 -0.649986)
			(size 0.4318 0.508)
			(layers "F.Cu" "F.Mask" "F.Paste")
			(net "GND")
		)
		(pad "2" smd rect
			(at -0.94996 0)
			(size 0.4318 0.508)
			(layers "F.Cu" "F.Mask" "F.Paste")
			(net "FM_SMERR_BUF_R_LED_N")
		)
		(pad "3" smd rect
			(at -0.94996 0.649986)
			(size 0.4318 0.508)
			(layers "F.Cu" "F.Mask" "F.Paste")
			(net "SMERR_LED_N")
		)
		(pad "4" smd rect
			(at 0.94996 0.649986)
			(size 0.4318 0.508)
			(layers "F.Cu" "F.Mask" "F.Paste")
			(net "GND")
		)
		(pad "5" smd rect
			(at 0.94996 0)
			(size 0.4318 0.508)
			(layers "F.Cu" "F.Mask" "F.Paste")
			(net "SMERR_LED")
		)
		(pad "6" smd rect
			(at 0.94996 -0.649986)
			(size 0.4318 0.508)
			(layers "F.Cu" "F.Mask" "F.Paste")
			(net "SMERR_LED")
		)
	)
	(footprint ""
		(layer "F.Cu")
		(at 395.388084 -390.652)
		(property "Reference" "R1102"
			(at 0 0 0)
			(layer "F.SilkS")
			(hide yes)
			(effects
				(font
					(size 1.27 1.27)
				)
			)
		)
		(property "Value" ""
			(at 0 0 0)
			(layer "F.Fab")
			(effects
				(font
					(size 1.27 1.27)
				)
			)
		)
		(duplicate_pad_numbers_are_jumpers no)
		(fp_line
			(start -0.32512 -0.175006)
			(end 0.32512 -0.175006)
			(stroke
				(width 0.1)
				(type default)
			)
			(layer "F.Fab")
		)
		(fp_line
			(start -0.32512 0.175006)
			(end -0.32512 -0.175006)
			(stroke
				(width 0.1)
				(type default)
			)
			(layer "F.Fab")
		)
		(fp_line
			(start 0.32512 -0.175006)
			(end 0.32512 0.175006)
			(stroke
				(width 0.1)
				(type default)
			)
			(layer "F.Fab")
		)
		(fp_line
			(start 0.32512 0.175006)
			(end -0.32512 0.175006)
			(stroke
				(width 0.1)
				(type default)
			)
			(layer "F.Fab")
		)
		(pad "1" smd rect
			(at -0.2667 0)
			(size 0.3048 0.381)
			(layers "F.Cu" "F.Mask" "F.Paste")
			(net "RT_CPU0_P3_ADDR1")
		)
		(pad "2" smd rect
			(at 0.2667 0 180)
			(size 0.3048 0.381)
			(layers "F.Cu" "F.Mask" "F.Paste")
			(net "GND")
		)
	)
)
